(kicad_pcb
	(version 20241229)
	(generator "pcbnew")
	(generator_version "9.0")
	(general
		(thickness 1.61)
		(legacy_teardrops no)
	)
	(paper "A3")
	(title_block
		(title "RDIMM DDR5 Tester")
		(date "2026-05-21")
		(rev "2.2.0")
		(company "Antmicro")
		(comment 9 "footprints 708-712 of 796")
	)
	(layers
		(0 "F.Cu" signal)
		(4 "In1.Cu" power)
		(6 "In2.Cu" mixed)
		(8 "In3.Cu" power)
		(10 "In4.Cu" mixed)
		(12 "In5.Cu" power)
		(14 "In6.Cu" mixed)
		(16 "In7.Cu" power)
		(18 "In8.Cu" power)
		(20 "In9.Cu" mixed)
		(22 "In10.Cu" power)
		(2 "B.Cu" signal)
		(9 "F.Adhes" user "F.Adhesive")
		(11 "B.Adhes" user "B.Adhesive")
		(13 "F.Paste" user)
		(15 "B.Paste" user)
		(5 "F.SilkS" user "F.Silkscreen")
		(7 "B.SilkS" user "B.Silkscreen")
		(1 "F.Mask" user)
		(3 "B.Mask" user)
		(17 "Dwgs.User" user "User.Drawings")
		(19 "Cmts.User" user "User.Comments")
		(21 "Eco1.User" user "User.Eco1")
		(23 "Eco2.User" user "User.Eco2")
		(25 "Edge.Cuts" user)
		(27 "Margin" user)
		(31 "F.CrtYd" user "F.Courtyard")
		(29 "B.CrtYd" user "B.Courtyard")
		(35 "F.Fab" user)
		(33 "B.Fab" user)
	)
	(footprint "antmicro-footprints:R_0402_1005Metric"
		(layer "B.Cu")
		(at 234.06 134.76 -90)
		(descr "Resistor SMD 0402")
		(tags "resistor SMD 0402")
		(property "Reference" "R127"
			(at 0.99 -0.215 90)
			(layer "B.SilkS")
			(effects
				(font
					(size 0.7 0.7)
					(thickness 0.15)
				)
				(justify left bottom mirror)
			)
		)
		(property "Value" "R_0R_0402"
			(at -1.011843 -1.772047 90)
			(layer "B.Fab")
			(effects
				(font
					(size 0.7 0.7)
					(thickness 0.15)
				)
				(justify left bottom mirror)
			)
		)
		(property "Datasheet" "https://industrial.panasonic.com/cdbs/www-data/pdf/RDA0000/AOA0000C301.pdf"
			(at 0 0 270)
			(layer "F.Fab")
			(hide yes)
			(effects
				(font
					(size 1.27 1.27)
					(thickness 0.15)
				)
			)
		)
		(property "MPN" "ERJ2GE0R00X"
			(at 0 0 270)
			(unlocked yes)
			(layer "B.Fab")
			(hide yes)
			(effects
				(font
					(size 1 1)
					(thickness 0.15)
				)
				(justify mirror)
			)
		)
		(property "Manufacturer" "Panasonic"
			(at 0 0 270)
			(unlocked yes)
			(layer "B.Fab")
			(hide yes)
			(effects
				(font
					(size 1 1)
					(thickness 0.15)
				)
				(justify mirror)
			)
		)
		(property "License" "Apache-2.0"
			(at 0 0 270)
			(unlocked yes)
			(layer "B.Fab")
			(hide yes)
			(effects
				(font
					(size 1 1)
					(thickness 0.15)
				)
				(justify mirror)
			)
		)
		(property "Author" "Antmicro"
			(at 0 0 270)
			(unlocked yes)
			(layer "B.Fab")
			(hide yes)
			(effects
				(font
					(size 1 1)
					(thickness 0.15)
				)
				(justify mirror)
			)
		)
		(property "Val" "0R"
			(at 0 0 270)
			(unlocked yes)
			(layer "B.Fab")
			(hide yes)
			(effects
				(font
					(size 1 1)
					(thickness 0.15)
				)
				(justify mirror)
			)
		)
		(property "Tolerance" "~"
			(at 0 0 270)
			(unlocked yes)
			(layer "B.Fab")
			(hide yes)
			(effects
				(font
					(size 1 1)
					(thickness 0.15)
				)
				(justify mirror)
			)
		)
		(property "Current" "1A"
			(at 0 0 270)
			(unlocked yes)
			(layer "B.Fab")
			(hide yes)
			(effects
				(font
					(size 1 1)
					(thickness 0.15)
				)
				(justify mirror)
			)
		)
		(sheetname "/I^{2}C + I3C/")
		(sheetfile "i2c.kicad_sch")
		(attr smd)
		(fp_rect
			(start -0.925 0.47)
			(end 0.925 -0.47)
			(stroke
				(width 0.05)
				(type default)
			)
			(fill no)
			(layer "B.CrtYd")
		)
		(fp_rect
			(start -0.5 0.25)
			(end 0.5 -0.25)
			(stroke
				(width 0.15)
				(type solid)
			)
			(fill no)
			(layer "B.Fab")
		)
		(fp_text user "${REFERENCE}"
			(at -0.95 -3.168 90)
			(layer "B.Fab")
			(effects
				(font
					(size 0.7 0.7)
					(thickness 0.15)
				)
				(justify left bottom mirror)
			)
		)
		(fp_text user "License: Apache-2.0"
			(at -0.95 -5.169 90)
			(layer "B.Fab")
			(effects
				(font
					(size 0.7 0.7)
					(thickness 0.15)
				)
				(justify left bottom mirror)
			)
		)
		(fp_text user "Author: Antmicro"
			(at -0.95 -4.169 90)
			(layer "B.Fab")
			(effects
				(font
					(size 0.7 0.7)
					(thickness 0.15)
				)
				(justify left bottom mirror)
			)
		)
		(pad "1" smd roundrect
			(at -0.48 0 270)
			(size 0.59 0.64)
			(layers "B.Cu" "B.Mask" "B.Paste")
			(roundrect_rratio 0.25)
			(net 201 "VDDSPD")
			(pintype "passive")
		)
		(pad "2" smd roundrect
			(at 0.48 0 270)
			(size 0.59 0.64)
			(layers "B.Cu" "B.Mask" "B.Paste")
			(roundrect_rratio 0.25)
			(net 797 "+1V8")
			(pintype "passive")
		)
	)
	(footprint "antmicro-footprints:C_0402_1005Metric"
		(layer "B.Cu")
		(at 173.53 150.689999 -90)
		(descr "Capacitor SMD 0402")
		(tags "capacitor SMD 0402")
		(property "Reference" "C316"
			(at 1.010001 -0.37 90)
			(layer "B.SilkS")
			(effects
				(font
					(size 0.7 0.7)
					(thickness 0.15)
				)
				(justify left bottom mirror)
			)
		)
		(property "Value" "C_100n_0402"
			(at -1.022927 -2.155213 90)
			(layer "B.Fab")
			(effects
				(font
					(size 0.7 0.7)
					(thickness 0.15)
				)
				(justify left bottom mirror)
			)
		)
		(property "Datasheet" "https://www.murata.com/products/productdetail?partno=GRM155R61H104KE14%23"
			(at 0 0 270)
			(layer "F.Fab")
			(hide yes)
			(effects
				(font
					(size 1.27 1.27)
					(thickness 0.15)
				)
			)
		)
		(property "MPN" "GRM155R61H104KE14D"
			(at 0 0 270)
			(unlocked yes)
			(layer "B.Fab")
			(hide yes)
			(effects
				(font
					(size 1 1)
					(thickness 0.15)
				)
				(justify mirror)
			)
		)
		(property "Manufacturer" "Murata"
			(at 0 0 270)
			(unlocked yes)
			(layer "B.Fab")
			(hide yes)
			(effects
				(font
					(size 1 1)
					(thickness 0.15)
				)
				(justify mirror)
			)
		)
		(property "License" "Apache-2.0"
			(at 0 0 270)
			(unlocked yes)
			(layer "B.Fab")
			(hide yes)
			(effects
				(font
					(size 1 1)
					(thickness 0.15)
				)
				(justify mirror)
			)
		)
		(property "Author" "Antmicro"
			(at 0 0 270)
			(unlocked yes)
			(layer "B.Fab")
			(hide yes)
			(effects
				(font
					(size 1 1)
					(thickness 0.15)
				)
				(justify mirror)
			)
		)
		(property "Val" "100n"
			(at 0 0 270)
			(unlocked yes)
			(layer "B.Fab")
			(hide yes)
			(effects
				(font
					(size 1 1)
					(thickness 0.15)
				)
				(justify mirror)
			)
		)
		(property "Voltage" "50V"
			(at 0 0 270)
			(unlocked yes)
			(layer "B.Fab")
			(hide yes)
			(effects
				(font
					(size 1 1)
					(thickness 0.15)
				)
				(justify mirror)
			)
		)
		(property "Dielectric" "X5R"
			(at 0 0 270)
			(unlocked yes)
			(layer "B.Fab")
			(hide yes)
			(effects
				(font
					(size 1 1)
					(thickness 0.15)
				)
				(justify mirror)
			)
		)
		(sheetname "/FPGA MGT Interface/")
		(sheetfile "fpga-mgt.kicad_sch")
		(attr smd)
		(fp_rect
			(start -0.925 0.47)
			(end 0.925 -0.47)
			(stroke
				(width 0.05)
				(type default)
			)
			(fill no)
			(layer "B.CrtYd")
		)
		(fp_line
			(start -0.494 0.25)
			(end 0.504 0.25)
			(stroke
				(width 0.15)
				(type solid)
			)
			(layer "B.Fab")
		)
		(fp_line
			(start 0.504 0.25)
			(end 0.504 -0.248)
			(stroke
				(width 0.15)
				(type solid)
			)
			(layer "B.Fab")
		)
		(fp_line
			(start -0.494 -0.248)
			(end -0.494 0.25)
			(stroke
				(width 0.15)
				(type solid)
			)
			(layer "B.Fab")
		)
		(fp_line
			(start 0.504 -0.248)
			(end -0.494 -0.248)
			(stroke
				(width 0.15)
				(type solid)
			)
			(layer "B.Fab")
		)
		(fp_text user "Author: Antmicro"
			(at -0.939 -3.399 90)
			(layer "B.Fab")
			(effects
				(font
					(size 0.7 0.7)
					(thickness 0.15)
				)
				(justify left bottom mirror)
			)
		)
		(fp_text user "License: Apache-2.0"
			(at -0.939 -5.799 90)
			(layer "B.Fab")
			(effects
				(font
					(size 0.7 0.7)
					(thickness 0.15)
				)
				(justify left bottom mirror)
			)
		)
		(fp_text user "${REFERENCE}"
			(at -0.939 -4.599 90)
			(layer "B.Fab")
			(effects
				(font
					(size 0.7 0.7)
					(thickness 0.15)
				)
				(justify left bottom mirror)
			)
		)
		(pad "1" smd roundrect
			(at -0.48 0 270)
			(size 0.59 0.64)
			(layers "B.Cu" "B.Mask" "B.Paste")
			(roundrect_rratio 0.25)
			(net 458 "HDMI_REC_CLK_N")
			(pintype "passive")
		)
		(pad "2" smd roundrect
			(at 0.48 0 270)
			(size 0.59 0.64)
			(layers "B.Cu" "B.Mask" "B.Paste")
			(roundrect_rratio 0.25)
			(net 489 "/FPGA MGT Interface/HDMI_REC_CLK_C_N")
			(pintype "passive")
		)
	)
	(footprint "antmicro-footprints:R_0402_1005Metric"
		(layer "B.Cu")
		(at 219.91 154.389 180)
		(descr "Resistor SMD 0402")
		(tags "resistor SMD 0402")
		(property "Reference" "R3"
			(at -2.5 -0.421 0)
			(layer "B.SilkS")
			(effects
				(font
					(size 0.7 0.7)
					(thickness 0.15)
				)
				(justify left bottom mirror)
			)
		)
		(property "Value" "R_2k2_0402"
			(at 6.885407 -0.258797 0)
			(layer "B.Fab")
			(effects
				(font
					(size 0.7 0.7)
					(thickness 0.15)
				)
				(justify left bottom mirror)
			)
		)
		(property "Datasheet" "https://www.bourns.com/docs/product-datasheets/cr.pdf"
			(at 0 0 180)
			(layer "F.Fab")
			(hide yes)
			(effects
				(font
					(size 1.27 1.27)
					(thickness 0.15)
				)
			)
		)
		(property "Manufacturer" "Bourns"
			(at 0 0 180)
			(unlocked yes)
			(layer "B.Fab")
			(hide yes)
			(effects
				(font
					(size 1 1)
					(thickness 0.15)
				)
				(justify mirror)
			)
		)
		(property "MPN" "CR0402-FX-2201GLF"
			(at 0 0 180)
			(unlocked yes)
			(layer "B.Fab")
			(hide yes)
			(effects
				(font
					(size 1 1)
					(thickness 0.15)
				)
				(justify mirror)
			)
		)
		(property "Val" "2k2"
			(at 0 0 180)
			(unlocked yes)
			(layer "B.Fab")
			(hide yes)
			(effects
				(font
					(size 1 1)
					(thickness 0.15)
				)
				(justify mirror)
			)
		)
		(property "License" "Apache-2.0"
			(at 0 0 180)
			(unlocked yes)
			(layer "B.Fab")
			(hide yes)
			(effects
				(font
					(size 1 1)
					(thickness 0.15)
				)
				(justify mirror)
			)
		)
		(property "Author" "Antmicro"
			(at 0 0 180)
			(unlocked yes)
			(layer "B.Fab")
			(hide yes)
			(effects
				(font
					(size 1 1)
					(thickness 0.15)
				)
				(justify mirror)
			)
		)
		(property "Tolerance" "1%"
			(at 0 0 180)
			(unlocked yes)
			(layer "B.Fab")
			(hide yes)
			(effects
				(font
					(size 1 1)
					(thickness 0.15)
				)
				(justify mirror)
			)
		)
		(sheetname "/HyperRAM + QSPI Flash/")
		(sheetfile "hyperram-flash.kicad_sch")
		(attr smd)
		(fp_rect
			(start -0.925 0.47)
			(end 0.925 -0.47)
			(stroke
				(width 0.05)
				(type default)
			)
			(fill no)
			(layer "B.CrtYd")
		)
		(fp_rect
			(start -0.5 0.25)
			(end 0.5 -0.25)
			(stroke
				(width 0.15)
				(type solid)
			)
			(fill no)
			(layer "B.Fab")
		)
		(fp_text user "${REFERENCE}"
			(at -0.95 -3.168 0)
			(layer "B.Fab")
			(effects
				(font
					(size 0.7 0.7)
					(thickness 0.15)
				)
				(justify left bottom mirror)
			)
		)
		(fp_text user "License: Apache-2.0"
			(at -0.95 -5.169 0)
			(layer "B.Fab")
			(effects
				(font
					(size 0.7 0.7)
					(thickness 0.15)
				)
				(justify left bottom mirror)
			)
		)
		(fp_text user "Author: Antmicro"
			(at -0.95 -4.169 0)
			(layer "B.Fab")
			(effects
				(font
					(size 0.7 0.7)
					(thickness 0.15)
				)
				(justify left bottom mirror)
			)
		)
		(pad "1" smd roundrect
			(at -0.48 0 180)
			(size 0.59 0.64)
			(layers "B.Cu" "B.Mask" "B.Paste")
			(roundrect_rratio 0.25)
			(net 797 "+1V8")
			(pintype "passive")
		)
		(pad "2" smd roundrect
			(at 0.48 0 180)
			(size 0.59 0.64)
			(layers "B.Cu" "B.Mask" "B.Paste")
			(roundrect_rratio 0.25)
			(net 350 "/FPGA Config/FLASH.~{CS}")
			(pintype "passive")
		)
	)
	(footprint "antmicro-footprints:C_0402_1005Metric_EIA"
		(layer "B.Cu")
		(at 190 154.5 -90)
		(descr "Capacitor SMD 0402 (1005 Metric), square (rectangular) end terminal, IPC_7351 nominal, (Body size source: IPC-SM-782 page 76, https://www.pcb-3d.com/wordpress/wp-content/uploads/ipc-sm-782a_amendment_1_and_2.pdf)")
		(tags "capacitor 0402")
		(property "Reference" "C88"
			(at -11.875 30.725 90)
			(layer "B.SilkS")
			(effects
				(font
					(size 0.7 0.7)
					(thickness 0.15)
				)
				(justify left bottom mirror)
			)
		)
		(property "Value" "C_1u_25V_0402"
			(at 0 -1.169 90)
			(layer "B.Fab")
			(effects
				(font
					(size 0.7 0.7)
					(thickness 0.15)
				)
				(justify left bottom mirror)
			)
		)
		(property "Datasheet" "https://www.murata.com/products/productdetail?partno=GRM155R61E105KE11%23"
			(at 0 0 270)
			(layer "F.Fab")
			(hide yes)
			(effects
				(font
					(size 1.27 1.27)
					(thickness 0.15)
				)
			)
		)
		(property "MPN" "GRM155R61E105KE11J"
			(at 0 0 270)
			(unlocked yes)
			(layer "B.Fab")
			(hide yes)
			(effects
				(font
					(size 1 1)
					(thickness 0.15)
				)
				(justify mirror)
			)
		)
		(property "Manufacturer" "Murata"
			(at 0 0 270)
			(unlocked yes)
			(layer "B.Fab")
			(hide yes)
			(effects
				(font
					(size 1 1)
					(thickness 0.15)
				)
				(justify mirror)
			)
		)
		(property "License" "Apache-2.0"
			(at 0 0 270)
			(unlocked yes)
			(layer "B.Fab")
			(hide yes)
			(effects
				(font
					(size 1 1)
					(thickness 0.15)
				)
				(justify mirror)
			)
		)
		(property "Author" "Antmicro"
			(at 0 0 270)
			(unlocked yes)
			(layer "B.Fab")
			(hide yes)
			(effects
				(font
					(size 1 1)
					(thickness 0.15)
				)
				(justify mirror)
			)
		)
		(property "Val" "1u"
			(at 0 0 270)
			(unlocked yes)
			(layer "B.Fab")
			(hide yes)
			(effects
				(font
					(size 1 1)
					(thickness 0.15)
				)
				(justify mirror)
			)
		)
		(property "Voltage" "25V"
			(at 0 0 270)
			(unlocked yes)
			(layer "B.Fab")
			(hide yes)
			(effects
				(font
					(size 1 1)
					(thickness 0.15)
				)
				(justify mirror)
			)
		)
		(property "Dielectric" "X5R"
			(at 0 0 270)
			(unlocked yes)
			(layer "B.Fab")
			(hide yes)
			(effects
				(font
					(size 1 1)
					(thickness 0.15)
				)
				(justify mirror)
			)
		)
		(sheetname "/FPGA power/")
		(sheetfile "fpga-power.kicad_sch")
		(attr smd)
		(fp_rect
			(start -0.95 0.45)
			(end 0.95 -0.45)
			(stroke
				(width 0.05)
				(type default)
			)
			(fill no)
			(layer "B.CrtYd")
		)
		(fp_line
			(start -0.5 0.25)
			(end 0.498 0.25)
			(stroke
				(width 0.15)
				(type solid)
			)
			(layer "B.Fab")
		)
		(fp_line
			(start 0.498 0.25)
			(end 0.498 -0.248)
			(stroke
				(width 0.15)
				(type solid)
			)
			(layer "B.Fab")
		)
		(fp_line
			(start -0.5 -0.248)
			(end -0.5 0.25)
			(stroke
				(width 0.15)
				(type solid)
			)
			(layer "B.Fab")
		)
		(fp_line
			(start 0.498 -0.248)
			(end -0.5 -0.248)
			(stroke
				(width 0.15)
				(type solid)
			)
			(layer "B.Fab")
		)
		(fp_text user "Author: Antmicro"
			(at -0.9656 -5.569 90)
			(layer "B.Fab")
			(effects
				(font
					(size 0.7 0.7)
					(thickness 0.15)
				)
				(justify left bottom mirror)
			)
		)
		(fp_text user "${REFERENCE}"
			(at -0.9656 -3.169 90)
			(layer "B.Fab")
			(effects
				(font
					(size 0.7 0.7)
					(thickness 0.15)
				)
				(justify left bottom mirror)
			)
		)
		(fp_text user "License: Apache-2.0"
			(at -0.9656 -4.369 90)
			(layer "B.Fab")
			(effects
				(font
					(size 0.7 0.7)
					(thickness 0.15)
				)
				(justify left bottom mirror)
			)
		)
		(pad "1" smd roundrect
			(at -0.5 0 180)
			(size 0.6 0.6)
			(layers "B.Cu" "B.Mask" "B.Paste")
			(roundrect_rratio 0.25)
			(net 1 "GND")
			(pintype "passive")
		)
		(pad "2" smd roundrect
			(at 0.498 0 270)
			(size 0.6 0.6)
			(layers "B.Cu" "B.Mask" "B.Paste")
			(roundrect_rratio 0.25)
			(net 553 "+0V85")
			(pintype "passive")
		)
	)
	(footprint "antmicro-footprints:R_0402_1005Metric"
		(layer "B.Cu")
		(at 238.424499 180.449 180)
		(descr "Resistor SMD 0402")
		(tags "resistor SMD 0402")
		(property "Reference" "R179"
			(at -3.95 -0.5 0)
			(layer "B.SilkS")
			(effects
				(font
					(size 0.7 0.7)
					(thickness 0.15)
				)
				(justify left bottom mirror)
			)
		)
		(property "Value" "R_0R_0402"
			(at -1.011843 -1.772047 0)
			(layer "B.Fab")
			(effects
				(font
					(size 0.7 0.7)
					(thickness 0.15)
				)
				(justify left bottom mirror)
			)
		)
		(property "Datasheet" "https://industrial.panasonic.com/cdbs/www-data/pdf/RDA0000/AOA0000C301.pdf"
			(at 0 0 180)
			(layer "F.Fab")
			(hide yes)
			(effects
				(font
					(size 1.27 1.27)
					(thickness 0.15)
				)
			)
		)
		(property "Manufacturer" "Panasonic"
			(at 0 0 180)
			(unlocked yes)
			(layer "B.Fab")
			(hide yes)
			(effects
				(font
					(size 1 1)
					(thickness 0.15)
				)
				(justify mirror)
			)
		)
		(property "MPN" "ERJ2GE0R00X"
			(at 0 0 180)
			(unlocked yes)
			(layer "B.Fab")
			(hide yes)
			(effects
				(font
					(size 1 1)
					(thickness 0.15)
				)
				(justify mirror)
			)
		)
		(property "Val" "0R"
			(at 0 0 180)
			(unlocked yes)
			(layer "B.Fab")
			(hide yes)
			(effects
				(font
					(size 1 1)
					(thickness 0.15)
				)
				(justify mirror)
			)
		)
		(property "License" "Apache-2.0"
			(at 0 0 180)
			(unlocked yes)
			(layer "B.Fab")
			(hide yes)
			(effects
				(font
					(size 1 1)
					(thickness 0.15)
				)
				(justify mirror)
			)
		)
		(property "Author" "Antmicro"
			(at 0 0 180)
			(unlocked yes)
			(layer "B.Fab")
			(hide yes)
			(effects
				(font
					(size 1 1)
					(thickness 0.15)
				)
				(justify mirror)
			)
		)
		(property "Tolerance" "~"
			(at 0 0 180)
			(unlocked yes)
			(layer "B.Fab")
			(hide yes)
			(effects
				(font
					(size 1 1)
					(thickness 0.15)
				)
				(justify mirror)
			)
		)
		(property "Current" "1A"
			(at 0 0 180)
			(unlocked yes)
			(layer "B.Fab")
			(hide yes)
			(effects
				(font
					(size 1 1)
					(thickness 0.15)
				)
				(justify mirror)
			)
		)
		(sheetname "/I^{2}C + I3C/")
		(sheetfile "i2c.kicad_sch")
		(attr smd exclude_from_bom dnp)
		(fp_rect
			(start -0.925 0.47)
			(end 0.925 -0.47)
			(stroke
				(width 0.05)
				(type default)
			)
			(fill no)
			(layer "B.CrtYd")
		)
		(fp_rect
			(start -0.5 0.25)
			(end 0.5 -0.25)
			(stroke
				(width 0.15)
				(type solid)
			)
			(fill no)
			(layer "B.Fab")
		)
		(fp_text user "License: Apache-2.0"
			(at -0.95 -5.169 0)
			(layer "B.Fab")
			(effects
				(font
					(size 0.7 0.7)
					(thickness 0.15)
				)
				(justify left bottom mirror)
			)
		)
		(fp_text user "Author: Antmicro"
			(at -0.95 -4.169 0)
			(layer "B.Fab")
			(effects
				(font
					(size 0.7 0.7)
					(thickness 0.15)
				)
				(justify left bottom mirror)
			)
		)
		(fp_text user "${REFERENCE}"
			(at -0.95 -3.168 0)
			(layer "B.Fab")
			(effects
				(font
					(size 0.7 0.7)
					(thickness 0.15)
				)
				(justify left bottom mirror)
			)
		)
		(pad "1" smd roundrect
			(at -0.48 0 180)
			(size 0.59 0.64)
			(layers "B.Cu" "B.Mask" "B.Paste")
			(roundrect_rratio 0.25)
			(net 749 "/I^{2}C + I3C/PWR.SCL")
			(pintype "passive")
		)
		(pad "2" smd roundrect
			(at 0.48 0 180)
			(size 0.59 0.64)
			(layers "B.Cu" "B.Mask" "B.Paste")
			(roundrect_rratio 0.25)
			(net 526 "/Debug FTDI + VNA/FTDI.SCL")
			(pintype "passive")
		)
	)
)
